(kicad_pcb
	(version 20260206)
	(generator "pcbnew")
	(generator_version "10.0")
	(general
		(thickness 1.6)
		(legacy_teardrops no)
	)
	(paper "A4")
	(title_block
		(title "03242023_DA0F0TMBIJ0_F0T_Motherboard_J_brd_V01_OCP.brd")
		(comment 1 "Grand Teton / footprint 1682 of 6105 (U1), pads 2036-2144 of 4677")
	)
	(layers
		(0 "F.Cu" signal "TOP")
		(4 "In1.Cu" signal "GND")
		(6 "In2.Cu" signal "IN1")
		(8 "In3.Cu" signal "GND1")
		(10 "In4.Cu" signal "IN2")
		(12 "In5.Cu" signal "GND2")
		(14 "In6.Cu" signal "IN3")
		(16 "In7.Cu" signal "GND3")
		(18 "In8.Cu" signal "VCC")
		(20 "In9.Cu" signal "VCC1")
		(22 "In10.Cu" signal "GND4")
		(24 "In11.Cu" signal "IN4")
		(26 "In12.Cu" signal "GND5")
		(28 "In13.Cu" signal "IN5")
		(30 "In14.Cu" signal "GND6")
		(32 "In15.Cu" signal "IN6")
		(34 "In16.Cu" signal "GND7")
		(2 "B.Cu" signal "BOTTOM")
		(9 "F.Adhes" user "F.Adhesive")
		(11 "B.Adhes" user "B.Adhesive")
		(13 "F.Paste" user "Package Geometry/Pastemask Top")
		(15 "B.Paste" user "Package Geometry/Pastemask Bottom")
		(5 "F.SilkS" user "Ref Des/Silkscreen Top")
		(7 "B.SilkS" user "Ref Des/Silkscreen Bottom")
		(1 "F.Mask" user "Board Geometry/Soldermask Top")
		(3 "B.Mask" user "Board Geometry/Soldermask Bottom")
		(17 "Dwgs.User" user "User.Drawings")
		(19 "Cmts.User" user "User.Comments")
		(21 "Eco1.User" user "User.Eco1")
		(23 "Eco2.User" user "User.Eco2")
		(25 "Edge.Cuts" user "Board Geometry/Outline")
		(27 "Margin" user)
		(31 "F.CrtYd" user "Package Geometry/Place Bound Top")
		(29 "B.CrtYd" user "Package Geometry/Place Bound Bottom")
		(35 "F.Fab" user "Ref Des/Assembly Top")
		(33 "B.Fab" user "Ref Des/Assembly Bottom")
	)
	(footprint ""
		(layer "F.Cu")
		(at 111.93018 -251.76988 90)
		(property "Reference" "U1"
			(at -74.913236 41.548812 0)
			(unlocked yes)
			(layer "F.SilkS")
			(effects
				(font
					(size 1.6002 1.1938)
					(thickness 0.1524)
				)
				(justify left)
			)
		)
		(property "Value" ""
			(at 0 0 90)
			(layer "F.Fab")
			(effects
				(font
					(size 1.27 1.27)
				)
			)
		)
		(duplicate_pad_numbers_are_jumpers no)
		(pad "CL19" smd circle
			(at -22.77491 5.818886 270)
			(size 0.4318 0.4318)
			(layers "F.Cu" "F.Mask" "F.Paste")
			(net "TP_DMI_CPU1_PCH_TX_DP<6>")
		)
		(pad "CL21" smd circle
			(at -21.147278 5.818886 270)
			(size 0.4318 0.4318)
			(layers "F.Cu" "F.Mask" "F.Paste")
			(net "CPU1_RSVD<107>")
		)
		(pad "CL23" smd circle
			(at -19.519392 5.818886 270)
			(size 0.4318 0.4318)
			(layers "F.Cu" "F.Mask" "F.Paste")
			(net "TP_I2C_S3M_RTC_CPU1_SCL")
		)
		(pad "CL25" smd circle
			(at -17.89176 5.818886 270)
			(size 0.4318 0.4318)
			(layers "F.Cu" "F.Mask" "F.Paste")
			(net "TP_H_SBLINK2_CPU1_PMSYNC")
		)
		(pad "CL60" smd circle
			(at 12.19454 5.928868 270)
			(size 0.4318 0.4318)
			(layers "F.Cu" "F.Mask" "F.Paste")
			(net "TP_CPU1_SPARE7")
		)
		(pad "CL62" smd circle
			(at 13.822426 5.928868 270)
			(size 0.4318 0.4318)
			(layers "F.Cu" "F.Mask" "F.Paste")
			(net "GND")
		)
		(pad "CL64" smd circle
			(at 15.450058 5.928868 270)
			(size 0.4318 0.4318)
			(layers "F.Cu" "F.Mask" "F.Paste")
			(net "CPU1_RSVD<110>")
		)
		(pad "CL66" smd circle
			(at 17.07769 5.928868 270)
			(size 0.4318 0.4318)
			(layers "F.Cu" "F.Mask" "F.Paste")
			(net "TP_CPU1_SSC_SYNC")
		)
		(pad "CL68" smd circle
			(at 18.705576 5.928868 270)
			(size 0.4318 0.4318)
			(layers "F.Cu" "F.Mask" "F.Paste")
			(net "NC_CPU1_PE3_APROBE<0>")
		)
		(pad "CL70" smd circle
			(at 20.333462 5.928868 270)
			(size 0.4318 0.4318)
			(layers "F.Cu" "F.Mask" "F.Paste")
			(net "TP_CPU1_SPARE12")
		)
		(pad "CL72" smd circle
			(at 21.961094 5.928868 270)
			(size 0.4318 0.4318)
			(layers "F.Cu" "F.Mask" "F.Paste")
			(net "PUD_XTAL_CPU1_MODE0")
		)
		(pad "CL74" smd circle
			(at 23.58898 5.928868 270)
			(size 0.4318 0.4318)
			(layers "F.Cu" "F.Mask" "F.Paste")
			(net "GND")
		)
		(pad "CL76" smd circle
			(at 25.216612 5.928868 270)
			(size 0.4318 0.4318)
			(layers "F.Cu" "F.Mask" "F.Paste")
			(net "Net_715")
		)
		(pad "CL78" smd circle
			(at 26.844498 5.928868 270)
			(size 0.4318 0.4318)
			(layers "F.Cu" "F.Mask" "F.Paste")
			(net "GND")
		)
		(pad "CL80" smd circle
			(at 28.472384 5.928868 270)
			(size 0.4318 0.4318)
			(layers "F.Cu" "F.Mask" "F.Paste")
			(net "GND")
		)
		(pad "CL82" smd circle
			(at 30.100016 5.928868 270)
			(size 0.4318 0.4318)
			(layers "F.Cu" "F.Mask" "F.Paste")
			(net "GND")
		)
		(pad "CL84" smd circle
			(at 31.727902 5.928868 270)
			(size 0.4318 0.4318)
			(layers "F.Cu" "F.Mask" "F.Paste")
			(net "PVCCIN_CPU1")
		)
		(pad "CL86" smd circle
			(at 33.355534 5.928868 270)
			(size 0.4318 0.4318)
			(layers "F.Cu" "F.Mask" "F.Paste")
			(net "PVCCIN_CPU1")
		)
		(pad "CL88" smd circle
			(at 34.98342 5.928868 270)
			(size 0.4318 0.4318)
			(layers "F.Cu" "F.Mask" "F.Paste")
			(net "PVCCIN_CPU1")
		)
		(pad "CL90" smd circle
			(at 36.611306 5.928868 270)
			(size 0.4318 0.4318)
			(layers "F.Cu" "F.Mask" "F.Paste")
			(net "PVCCIN_CPU1")
		)
		(pad "CM2" smd circle
			(at -36.611306 6.288532 270)
			(size 0.4318 0.4318)
			(layers "F.Cu" "F.Mask" "F.Paste")
			(net "UPI_CPU0_CPU1_P0P1_DP<18>")
		)
		(pad "CM4" smd circle
			(at -34.98342 6.288532 270)
			(size 0.4318 0.4318)
			(layers "F.Cu" "F.Mask" "F.Paste")
			(net "GND")
		)
		(pad "CM6" smd circle
			(at -33.355534 6.288532 270)
			(size 0.4318 0.4318)
			(layers "F.Cu" "F.Mask" "F.Paste")
			(net "UPI_CPU1_CPU0_P1P0_DN<17>")
		)
		(pad "CM8" smd circle
			(at -31.727902 6.288532 270)
			(size 0.4318 0.4318)
			(layers "F.Cu" "F.Mask" "F.Paste")
			(net "GND")
		)
		(pad "CM10" smd circle
			(at -30.100016 6.288532 270)
			(size 0.4318 0.4318)
			(layers "F.Cu" "F.Mask" "F.Paste")
			(net "P5E_CPU1_PE1_RX_DP<1>")
		)
		(pad "CM12" smd circle
			(at -28.472384 6.288532 270)
			(size 0.4318 0.4318)
			(layers "F.Cu" "F.Mask" "F.Paste")
			(net "GND")
		)
		(pad "CM14" smd circle
			(at -26.844498 6.288532 270)
			(size 0.4318 0.4318)
			(layers "F.Cu" "F.Mask" "F.Paste")
			(net "P5E_CPU1_PE1_TX_DP<1>")
		)
		(pad "CM16" smd circle
			(at -25.216612 6.288532 270)
			(size 0.4318 0.4318)
			(layers "F.Cu" "F.Mask" "F.Paste")
			(net "GND")
		)
		(pad "CM18" smd circle
			(at -23.58898 6.288532 270)
			(size 0.4318 0.4318)
			(layers "F.Cu" "F.Mask" "F.Paste")
			(net "TP_DMI_CPU1_PCH_TX_DP<7>")
		)
		(pad "CM20" smd circle
			(at -21.961094 6.288532 270)
			(size 0.4318 0.4318)
			(layers "F.Cu" "F.Mask" "F.Paste")
			(net "GND")
		)
		(pad "CM22" smd circle
			(at -20.333462 6.288532 270)
			(size 0.4318 0.4318)
			(layers "F.Cu" "F.Mask" "F.Paste")
			(net "GND")
		)
		(pad "CM24" smd circle
			(at -18.705576 6.288532 270)
			(size 0.4318 0.4318)
			(layers "F.Cu" "F.Mask" "F.Paste")
			(net "GND")
		)
		(pad "CM26" smd circle
			(at -17.07769 6.288532 270)
			(size 0.4318 0.4318)
			(layers "F.Cu" "F.Mask" "F.Paste")
			(net "TP_H_SBLINK3_CPU1_PMDOWN")
		)
		(pad "CM61" smd circle
			(at 13.008356 6.398514 270)
			(size 0.4318 0.4318)
			(layers "F.Cu" "F.Mask" "F.Paste")
			(net "GND")
		)
		(pad "CM63" smd circle
			(at 14.635988 6.398514 270)
			(size 0.4318 0.4318)
			(layers "F.Cu" "F.Mask" "F.Paste")
			(net "CPU1_RSVD<115>")
		)
		(pad "CM65" smd circle
			(at 16.263874 6.398514 270)
			(size 0.4318 0.4318)
			(layers "F.Cu" "F.Mask" "F.Paste")
			(net "GND")
		)
		(pad "CM67" smd circle
			(at 17.89176 6.398514 270)
			(size 0.4318 0.4318)
			(layers "F.Cu" "F.Mask" "F.Paste")
			(net "GND")
		)
		(pad "CM69" smd circle
			(at 19.519392 6.398514 270)
			(size 0.4318 0.4318)
			(layers "F.Cu" "F.Mask" "F.Paste")
			(net "NC_CPU1_PE3_APROBE<1>")
		)
		(pad "CM71" smd circle
			(at 21.147278 6.398514 270)
			(size 0.4318 0.4318)
			(layers "F.Cu" "F.Mask" "F.Paste")
			(net "SMB_S3M_CPU1_PIROM_3V3AUX_SDA_1")
		)
		(pad "CM73" smd circle
			(at 22.77491 6.398514 270)
			(size 0.4318 0.4318)
			(layers "F.Cu" "F.Mask" "F.Paste")
			(net "PVCCFA_EHV_FIVRA_CPU1")
		)
		(pad "CM75" smd circle
			(at 24.402796 6.398514 270)
			(size 0.4318 0.4318)
			(layers "F.Cu" "F.Mask" "F.Paste")
			(net "Net_739")
		)
		(pad "CM77" smd circle
			(at 26.030682 6.398514 270)
			(size 0.4318 0.4318)
			(layers "F.Cu" "F.Mask" "F.Paste")
			(net "Net_717")
		)
		(pad "CM79" smd circle
			(at 27.658314 6.398514 270)
			(size 0.4318 0.4318)
			(layers "F.Cu" "F.Mask" "F.Paste")
			(net "GND")
		)
		(pad "CM81" smd circle
			(at 29.2862 6.398514 270)
			(size 0.4318 0.4318)
			(layers "F.Cu" "F.Mask" "F.Paste")
			(net "GND")
		)
		(pad "CM83" smd circle
			(at 30.914086 6.398514 270)
			(size 0.4318 0.4318)
			(layers "F.Cu" "F.Mask" "F.Paste")
			(net "GND")
		)
		(pad "CM85" smd circle
			(at 32.541718 6.398514 270)
			(size 0.4318 0.4318)
			(layers "F.Cu" "F.Mask" "F.Paste")
			(net "GND")
		)
		(pad "CM87" smd circle
			(at 34.169604 6.398514 270)
			(size 0.4318 0.4318)
			(layers "F.Cu" "F.Mask" "F.Paste")
			(net "PVCCIN_CPU1")
		)
		(pad "CM89" smd circle
			(at 35.797236 6.398514 270)
			(size 0.4318 0.4318)
			(layers "F.Cu" "F.Mask" "F.Paste")
			(net "PVCCIN_CPU1")
		)
		(pad "CM91" smd oval
			(at 37.425122 6.398514)
			(size 0.381 0.4826)
			(drill
				(offset 0 -0.0508)
			)
			(layers "F.Cu" "F.Mask" "F.Paste")
			(net "PVCCIN_CPU1")
		)
		(pad "CN1" smd oval
			(at -37.425122 6.758686 180)
			(size 0.381 0.4826)
			(drill
				(offset 0 -0.0508)
			)
			(layers "F.Cu" "F.Mask" "F.Paste")
			(net "UPI_CPU0_CPU1_P0P1_DN<17>")
		)
		(pad "CN3" smd circle
			(at -35.797236 6.758686 270)
			(size 0.4318 0.4318)
			(layers "F.Cu" "F.Mask" "F.Paste")
			(net "PVCCINFAON_CPU1")
		)
		(pad "CN5" smd circle
			(at -34.169604 6.758686 270)
			(size 0.4318 0.4318)
			(layers "F.Cu" "F.Mask" "F.Paste")
			(net "UPI_CPU1_CPU0_P1P0_DN<16>")
		)
		(pad "CN7" smd circle
			(at -32.541718 6.758686 270)
			(size 0.4318 0.4318)
			(layers "F.Cu" "F.Mask" "F.Paste")
			(net "PVCCINFAON_CPU1")
		)
		(pad "CN9" smd circle
			(at -30.914086 6.758686 270)
			(size 0.4318 0.4318)
			(layers "F.Cu" "F.Mask" "F.Paste")
			(net "P5E_CPU1_PE1_RX_DP<0>")
		)
		(pad "CN11" smd circle
			(at -29.2862 6.758686 270)
			(size 0.4318 0.4318)
			(layers "F.Cu" "F.Mask" "F.Paste")
			(net "PVCCINFAON_CPU1")
		)
		(pad "CN13" smd circle
			(at -27.658314 6.758686 270)
			(size 0.4318 0.4318)
			(layers "F.Cu" "F.Mask" "F.Paste")
			(net "P5E_CPU1_PE1_TX_DN<1>")
		)
		(pad "CN15" smd circle
			(at -26.030682 6.758686 270)
			(size 0.4318 0.4318)
			(layers "F.Cu" "F.Mask" "F.Paste")
			(net "PVCCINFAON_CPU1")
		)
		(pad "CN17" smd circle
			(at -24.402796 6.758686 270)
			(size 0.4318 0.4318)
			(layers "F.Cu" "F.Mask" "F.Paste")
			(net "TP_DMI_CPU1_PCH_TX_DN<7>")
		)
		(pad "CN19" smd circle
			(at -22.77491 6.758686 270)
			(size 0.4318 0.4318)
			(layers "F.Cu" "F.Mask" "F.Paste")
			(net "PVCCINFAON_CPU1")
		)
		(pad "CN21" smd circle
			(at -21.147278 6.758686 270)
			(size 0.4318 0.4318)
			(layers "F.Cu" "F.Mask" "F.Paste")
			(net "TP_FM_IBL_SLPS4_CPU1_R_N")
		)
		(pad "CN23" smd circle
			(at -19.519392 6.758686 270)
			(size 0.4318 0.4318)
			(layers "F.Cu" "F.Mask" "F.Paste")
			(net "NC_FM_IBL_ADR_ACK_CPU1")
		)
		(pad "CN25" smd circle
			(at -17.89176 6.758686 270)
			(size 0.4318 0.4318)
			(layers "F.Cu" "F.Mask" "F.Paste")
			(net "H_CPU0_PMDOWN_CPU1")
		)
		(pad "CN60" smd circle
			(at 12.19454 6.868668 270)
			(size 0.4318 0.4318)
			(layers "F.Cu" "F.Mask" "F.Paste")
			(net "NC_CPU1_LGSSPARE1")
		)
		(pad "CN62" smd circle
			(at 13.822426 6.868668 270)
			(size 0.4318 0.4318)
			(layers "F.Cu" "F.Mask" "F.Paste")
			(net "CPU1_RSVD<120>")
		)
		(pad "CN64" smd circle
			(at 15.450058 6.868668 270)
			(size 0.4318 0.4318)
			(layers "F.Cu" "F.Mask" "F.Paste")
			(net "PVCCINFAON_CPU1")
		)
		(pad "CN66" smd circle
			(at 17.07769 6.868668 270)
			(size 0.4318 0.4318)
			(layers "F.Cu" "F.Mask" "F.Paste")
			(net "PVCCINFAON_CPU1")
		)
		(pad "CN68" smd circle
			(at 18.705576 6.868668 270)
			(size 0.4318 0.4318)
			(layers "F.Cu" "F.Mask" "F.Paste")
			(net "GND")
		)
		(pad "CN70" smd circle
			(at 20.333462 6.868668 270)
			(size 0.4318 0.4318)
			(layers "F.Cu" "F.Mask" "F.Paste")
			(net "GND")
		)
		(pad "CN72" smd circle
			(at 21.961094 6.868668 270)
			(size 0.4318 0.4318)
			(layers "F.Cu" "F.Mask" "F.Paste")
			(net "GND")
		)
		(pad "CN74" smd circle
			(at 23.58898 6.868668 270)
			(size 0.4318 0.4318)
			(layers "F.Cu" "F.Mask" "F.Paste")
			(net "GND")
		)
		(pad "CN76" smd circle
			(at 25.216612 6.868668 270)
			(size 0.4318 0.4318)
			(layers "F.Cu" "F.Mask" "F.Paste")
			(net "GND")
		)
		(pad "CN78" smd circle
			(at 26.844498 6.868668 270)
			(size 0.4318 0.4318)
			(layers "F.Cu" "F.Mask" "F.Paste")
			(net "PVCCFA_EHV_FIVRA_CPU1")
		)
		(pad "CN80" smd circle
			(at 28.472384 6.868668 270)
			(size 0.4318 0.4318)
			(layers "F.Cu" "F.Mask" "F.Paste")
			(net "GND")
		)
		(pad "CN82" smd circle
			(at 30.100016 6.868668 270)
			(size 0.4318 0.4318)
			(layers "F.Cu" "F.Mask" "F.Paste")
			(net "GND")
		)
		(pad "CN84" smd circle
			(at 31.727902 6.868668 270)
			(size 0.4318 0.4318)
			(layers "F.Cu" "F.Mask" "F.Paste")
			(net "GND")
		)
		(pad "CN86" smd circle
			(at 33.355534 6.868668 270)
			(size 0.4318 0.4318)
			(layers "F.Cu" "F.Mask" "F.Paste")
			(net "GND")
		)
		(pad "CN88" smd circle
			(at 34.98342 6.868668 270)
			(size 0.4318 0.4318)
			(layers "F.Cu" "F.Mask" "F.Paste")
			(net "PVCCIN_CPU1")
		)
		(pad "CN90" smd circle
			(at 36.611306 6.868668 270)
			(size 0.4318 0.4318)
			(layers "F.Cu" "F.Mask" "F.Paste")
			(net "PVCCIN_CPU1")
		)
		(pad "CP2" smd circle
			(at -36.611306 7.228332 270)
			(size 0.4318 0.4318)
			(layers "F.Cu" "F.Mask" "F.Paste")
			(net "UPI_CPU0_CPU1_P0P1_DP<17>")
		)
		(pad "CP4" smd circle
			(at -34.98342 7.228332 270)
			(size 0.4318 0.4318)
			(layers "F.Cu" "F.Mask" "F.Paste")
			(net "GND")
		)
		(pad "CP6" smd circle
			(at -33.355534 7.228332 270)
			(size 0.4318 0.4318)
			(layers "F.Cu" "F.Mask" "F.Paste")
			(net "UPI_CPU1_CPU0_P1P0_DP<16>")
		)
		(pad "CP8" smd circle
			(at -31.727902 7.228332 270)
			(size 0.4318 0.4318)
			(layers "F.Cu" "F.Mask" "F.Paste")
			(net "GND")
		)
		(pad "CP10" smd circle
			(at -30.100016 7.228332 270)
			(size 0.4318 0.4318)
			(layers "F.Cu" "F.Mask" "F.Paste")
			(net "P5E_CPU1_PE1_RX_DN<0>")
		)
		(pad "CP12" smd circle
			(at -28.472384 7.228332 270)
			(size 0.4318 0.4318)
			(layers "F.Cu" "F.Mask" "F.Paste")
			(net "GND")
		)
		(pad "CP14" smd circle
			(at -26.844498 7.228332 270)
			(size 0.4318 0.4318)
			(layers "F.Cu" "F.Mask" "F.Paste")
			(net "P5E_CPU1_PE1_TX_DN<0>")
		)
		(pad "CP16" smd circle
			(at -25.216612 7.228332 270)
			(size 0.4318 0.4318)
			(layers "F.Cu" "F.Mask" "F.Paste")
			(net "GND")
		)
		(pad "CP18" smd circle
			(at -23.58898 7.228332 270)
			(size 0.4318 0.4318)
			(layers "F.Cu" "F.Mask" "F.Paste")
			(net "GND")
		)
		(pad "CP20" smd circle
			(at -21.961094 7.228332 270)
			(size 0.4318 0.4318)
			(layers "F.Cu" "F.Mask" "F.Paste")
			(net "H_CPU1_PM_FAST_WAKE_N")
		)
		(pad "CP22" smd circle
			(at -20.333462 7.228332 270)
			(size 0.4318 0.4318)
			(layers "F.Cu" "F.Mask" "F.Paste")
			(net "TP_JTAG_CPU1_PLD_TDO_R")
		)
		(pad "CP24" smd circle
			(at -18.705576 7.228332 270)
			(size 0.4318 0.4318)
			(layers "F.Cu" "F.Mask" "F.Paste")
			(net "NC_FM_IBL_ADR_COMPLETE_CPU1_R")
		)
		(pad "CP26" smd circle
			(at -17.07769 7.228332 270)
			(size 0.4318 0.4318)
			(layers "F.Cu" "F.Mask" "F.Paste")
			(net "TP_H_SBLINK2_CPU1_PMDOWN")
		)
		(pad "CP61" smd circle
			(at 13.008356 7.338314 270)
			(size 0.4318 0.4318)
			(layers "F.Cu" "F.Mask" "F.Paste")
			(net "NC_CPU1_LGSSPARE5")
		)
		(pad "CP63" smd circle
			(at 14.635988 7.338314 270)
			(size 0.4318 0.4318)
			(layers "F.Cu" "F.Mask" "F.Paste")
			(net "PVCCINFAON_CPU1")
		)
		(pad "CP65" smd circle
			(at 16.263874 7.338314 270)
			(size 0.4318 0.4318)
			(layers "F.Cu" "F.Mask" "F.Paste")
			(net "PVCCINFAON_CPU1")
		)
		(pad "CP67" smd circle
			(at 17.89176 7.338314 270)
			(size 0.4318 0.4318)
			(layers "F.Cu" "F.Mask" "F.Paste")
			(net "PVCCINFAON_CPU1")
		)
		(pad "CP69" smd circle
			(at 19.519392 7.338314 270)
			(size 0.4318 0.4318)
			(layers "F.Cu" "F.Mask" "F.Paste")
			(net "NC_CPU1_UPI3_APROBE<0>")
		)
		(pad "CP71" smd circle
			(at 21.147278 7.338314 270)
			(size 0.4318 0.4318)
			(layers "F.Cu" "F.Mask" "F.Paste")
			(net "PD_PIROM_CPU1_ADDR2")
		)
		(pad "CP73" smd circle
			(at 22.77491 7.338314 270)
			(size 0.4318 0.4318)
			(layers "F.Cu" "F.Mask" "F.Paste")
			(net "PVCCFA_EHV_FIVRA_CPU1")
		)
		(pad "CP75" smd circle
			(at 24.402796 7.338314 270)
			(size 0.4318 0.4318)
			(layers "F.Cu" "F.Mask" "F.Paste")
			(net "GND")
		)
		(pad "CP77" smd circle
			(at 26.030682 7.338314 270)
			(size 0.4318 0.4318)
			(layers "F.Cu" "F.Mask" "F.Paste")
			(net "GND")
		)
		(pad "CP79" smd circle
			(at 27.658314 7.338314 270)
			(size 0.4318 0.4318)
			(layers "F.Cu" "F.Mask" "F.Paste")
			(net "GND")
		)
		(pad "CP81" smd circle
			(at 29.2862 7.338314 270)
			(size 0.4318 0.4318)
			(layers "F.Cu" "F.Mask" "F.Paste")
			(net "GND")
		)
		(pad "CP83" smd circle
			(at 30.914086 7.338314 270)
			(size 0.4318 0.4318)
			(layers "F.Cu" "F.Mask" "F.Paste")
			(net "GND")
		)
		(pad "CP85" smd circle
			(at 32.541718 7.338314 270)
			(size 0.4318 0.4318)
			(layers "F.Cu" "F.Mask" "F.Paste")
			(net "P5E_CPU1_PE3_TX_DN<15>")
		)
		(pad "CP87" smd circle
			(at 34.169604 7.338314 270)
			(size 0.4318 0.4318)
			(layers "F.Cu" "F.Mask" "F.Paste")
			(net "GND")
		)
		(pad "CP89" smd circle
			(at 35.797236 7.338314 270)
			(size 0.4318 0.4318)
			(layers "F.Cu" "F.Mask" "F.Paste")
			(net "PVCCIN_CPU1")
		)
		(pad "CP91" smd oval
			(at 37.425122 7.338314)
			(size 0.381 0.4826)
			(drill
				(offset 0 -0.0508)
			)
			(layers "F.Cu" "F.Mask" "F.Paste")
			(net "GND")
		)
		(pad "CR1" smd oval
			(at -37.425122 7.698486 180)
			(size 0.381 0.4826)
			(drill
				(offset 0 -0.0508)
			)
			(layers "F.Cu" "F.Mask" "F.Paste")
			(net "GND")
		)
		(pad "CR3" smd circle
			(at -35.797236 7.698486 270)
			(size 0.4318 0.4318)
			(layers "F.Cu" "F.Mask" "F.Paste")
			(net "UPI_CPU0_CPU1_P0P1_DN<16>")
		)
	)
)
